FILE_TYPE = CONNECTIVITY;
{Allegro Design Entry HDL 17.2-2016 S081 (4005846) 1/11/2022}
"PAGE_NUMBER" = 68;
0"NC";
1"PVCCIN_CPU1\g";
2"PVCCINFAON_CPU1\g";
3"PVCCD_HV_CPU1\g";
4"PVNN_MAIN_CPU1\g";
5"PVPP_HBM_CPU1\g";
6"P3V3_AUX\g";
7"PVCCINFAON_CPU1\g";
8"PVNN_MAIN_CPU1\g";
9"PVCCFA_EHV_CPU1\g";
10"GND\g";
%"SOCKET4677_AZIF0045P001C01CS"
"28","(-875,2325)","0","pure_quanta","I1";
;
PART_NUMBER"DGA^7000023"
PART_TYPE"SMLF"
MATERIAL"IO"
VALUE"SOCKET4677_AZIF0045-P001C01CS"
$LOCATION"U1"
CDS_LIB"pure_quanta"
NEEDS_NO_SIZE"TRUE"
CDS_LMAN_SYM_OUTLINE"-1050,1150,1050,-1100"
CDS_LOCATION"U1"
$SEC"28"
CDS_SEC"28";
"VCCINFAON33"
$PN"AY18"2;
"VCCINFAON34"
$PN"BA15"2;
"VCCINFAON35"
$PN"BC60"2;
"VCCINFAON36"
$PN"BE15"2;
"VCCINFAON37"
$PN"BE60"2;
"VCCINFAON38"
$PN"BG60"2;
"VCCINFAON39"
$PN"BJ15"2;
"VCCINFAON40"
$PN"BJ60"2;
"VCCINFAON41"
$PN"BK61"2;
"VCCINFAON42"
$PN"BN15"2;
"VCCINFAON43"
$PN"CA15"2;
"VCCINFAON44"
$PN"CE19"2;
"VCCINFAON45"
$PN"CJ11"2;
"VCCINFAON46"
$PN"CJ19"2;
"VCCINFAON47"
$PN"CN19"2;
"VCCINFAON48"
$PN"CP63"2;
"VCCINFAON49"
$PN"CT63"2;
"VCCINFAON50"
$PN"CV61"2;
"VCCINFAON51"
$PN"CV63"2;
"VCCINFAON52"
$PN"CW62"2;
"VCCINFAON53"
$PN"DA21"2;
"VCCIN0"
$PN"BD91"1;
"VCCIN1"
$PN"BE86"1;
"VCCIN2"
$PN"BE88"1;
"VCCIN3"
$PN"BE90"1;
"VCCIN4"
$PN"BF85"1;
"VCCIN5"
$PN"BF87"1;
"VCCIN6"
$PN"BF89"1;
"VCCIN7"
$PN"BF91"1;
"VCCIN8"
$PN"BG84"1;
"VCCIN9"
$PN"BG86"1;
"VCCIN10"
$PN"BG88"1;
"VCCIN11"
$PN"BG90"1;
"VCCIN12"
$PN"BH85"1;
"VCCIN13"
$PN"BH87"1;
"VCCIN14"
$PN"BH89"1;
"VCCIN15"
$PN"BH91"1;
"VCCIN16"
$PN"BK81"1;
"VCCIN17"
$PN"BK83"1;
"VCCIN18"
$PN"BK85"1;
"VCCIN19"
$PN"BK87"1;
"VCCIN20"
$PN"BK89"1;
"VCCIN21"
$PN"BK91"1;
"VCCIN22"
$PN"BL80"1;
"VCCIN23"
$PN"BL82"1;
"VCCIN24"
$PN"BL84"1;
"VCCIN25"
$PN"BL86"1;
"VCCIN26"
$PN"BL88"1;
"VCCIN27"
$PN"BL90"1;
"VCCIN28"
$PN"BM79"1;
"VCCIN29"
$PN"BM81"1;
"VCCIN30"
$PN"BM83"1;
"VCCIN31"
$PN"BM85"1;
"VCCIN32"
$PN"BM87"1;
"VCCIN33"
$PN"BM89"1;
"VCCIN34"
$PN"BM91"1;
"VCCIN35"
$PN"BN33"1;
"VCCIN36"
$PN"BN35"1;
"VCCIN37"
$PN"BN37"1;
"VCCIN38"
$PN"BN39"1;
"VCCIN39"
$PN"BN41"1;
%"VCC_CORE"
"1","(2050,3525)","0","logical_power","I10";
;
HDL_POWER"PVCCD_HV_CPU1"
CDS_LIB"logical_power";
"A"3;
%"VCC_CORE"
"1","(5300,875)","0","logical_power","I11";
;
HDL_POWER"PVCCFA_EHV_CPU1"
CDS_LIB"logical_power";
"A"9;
%"VCC_CORE"
"1","(5300,1525)","0","logical_power","I12";
;
HDL_POWER"PVNN_MAIN_CPU1"
CDS_LIB"logical_power";
"A"8;
%"VCC_CORE"
"1","(4950,3975)","0","logical_power","I13";
;
HDL_POWER"PVCCINFAON_CPU1"
CDS_LIB"logical_power";
"A"7;
%"VCC_CORE"
"1","(-2325,3525)","0","logical_power","I2";
;
HDL_POWER"PVCCIN_CPU1"
CDS_LIB"logical_power";
"A"1;
%"VCC_CORE"
"1","(575,3525)","0","logical_power","I3";
;
HDL_POWER"PVCCINFAON_CPU1"
CDS_LIB"logical_power";
"A"2;
%"Q_CAP"
"1","(1350,1075)","0","pure_quanta","I4";
;
PART_NUMBER"CH6101MEB01"
TOLERANCE"20%"
VALUE"10UF"
MATERIAL"X6S"
VOLTAGE"6.3V"
PACK_TYPE"C0402"
$LOCATION"C71"
CDS_LIB"pure_quanta"
CDS_LOCATION"C71"
$SEC"1"
CDS_SEC"1";
"B"
$PN"2"10;
"A"
$PN"1"6;
%"UNIVERSAL_GND"
"1","(1350,800)","0","logical_power","I5";
;
CDS_LIB"logical_power"
HDL_POWER"GND";
"A"10;
%"VCC_CORE"
"1","(1350,1425)","0","logical_power","I6";
;
HDL_POWER"P3V3_AUX"
CDS_LIB"logical_power";
"A"6;
%"VCC_CORE"
"1","(2050,1100)","0","logical_power","I7";
;
HDL_POWER"PVPP_HBM_CPU1"
CDS_LIB"logical_power";
"A"5;
%"SOCKET4677_AZIF0045P001C01CS"
"29","(3500,1925)","0","pure_quanta","I8";
;
PART_NUMBER"DGA^7000023"
PART_TYPE"SMLF"
MATERIAL"IO"
VALUE"SOCKET4677_AZIF0045-P001C01CS"
$LOCATION"U1"
CDS_LIB"pure_quanta"
NEEDS_NO_SIZE"TRUE"
CDS_LMAN_SYM_OUTLINE"-1050,1800,1050,-1750"
CDS_LOCATION"U1"
$SEC"29"
CDS_SEC"29";
"VPP_HBM4"
$PN"CC68"5;
"VPP_HBM3"
$PN"CD67"5;
"VPP_HBM2"
$PN"CE68"5;
"VPP_HBM1"
$PN"CF67"5;
"VPP_HBM"
$PN"CG68"5;
"VCCVNN0"
$PN"BA19"4;
"VCCVNN1"
$PN"BE19"4;
"VCCVNN2"
$PN"BJ19"8;
"VCCVNN3"
$PN"BN19"8;
"VCCINFAON0"
$PN"CE15"7;
"VCCINFAON1"
$PN"CJ15"7;
"VCCINFAON2"
$PN"CJ3"7;
"VCCINFAON3"
$PN"CJ7"7;
"VCCINFAON4"
$PN"CN11"7;
"VCCINFAON5"
$PN"CN15"7;
"VCCINFAON6"
$PN"CN3"7;
"VCCINFAON7"
$PN"CN64"7;
"VCCINFAON8"
$PN"CN66"7;
"VCCINFAON9"
$PN"CN7"7;
"VCCINFAON10"
$PN"CP65"7;
"VCCINFAON11"
$PN"CP67"7;
"VCCINFAON12"
$PN"CT65"7;
"VCCINFAON13"
$PN"CT67"7;
"VCCINFAON14"
$PN"CU11"7;
"VCCINFAON15"
$PN"CU15"7;
"VCCINFAON16"
$PN"CU3"7;
"VCCINFAON17"
$PN"CU64"7;
"VCCINFAON18"
$PN"CU7"7;
"VCCINFAON19"
$PN"CV65"7;
"VCCINFAON20"
$PN"CV67"7;
"VCCINFAON21"
$PN"CW66"7;
"VCCINFAON22"
$PN"CY65"7;
"VCCINFAON23"
$PN"CY67"7;
"VCCINFAON24"
$PN"DA11"7;
"VCCINFAON25"
$PN"DA15"7;
"VCCINFAON26"
$PN"DA64"7;
"VCCINFAON27"
$PN"DE11"7;
"VCCINFAON28"
$PN"DE15"7;
"VCCINFAON29"
$PN"DE3"7;
"VCCINFAON30"
$PN"DJ15"7;
"VCCINFAON31"
$PN"DJ3"7;
"VCCINFAON32"
$PN"DJ7"7;
"VCCINFAON54"
$PN"CR66"7;
"VCCINFAON55"
$PN"CW64"7;
"VCCINFAON56"
$PN"DA3"7;
"VCCINFAON57"
$PN"DA7"7;
"VCCINFAON58"
$PN"DE7"7;
"VCCINFAON59"
$PN"DJ11"7;
"VCCFA_EHV0"
$PN"AA3"9;
"VCCFA_EHV1"
$PN"AE3"9;
"VCCFA_EHV2"
$PN"AJ3"9;
"VCCFA_EHV3"
$PN"AN3"9;
"VCCFA_EHV4"
$PN"AT61"9;
"VCCFA_EHV5"
$PN"AU60"9;
"VCCFA_EHV6"
$PN"AV61"9;
"VCCFA_EHV7"
$PN"AW60"9;
"VCCFA_EHV9"
$PN"U3"9;
"VCCFA_EHV8"
$PN"N3"9;
"VCCD_HV0"
$PN"AT36"3;
"VCCD_HV1"
$PN"AT55"3;
"VCCD_HV2"
$PN"AU3"3;
"VCCD_HV3"
$PN"AU35"3;
"VCCD_HV4"
$PN"AU54"3;
"VCCD_HV5"
$PN"AU7"3;
"VCCD_HV6"
$PN"AV34"3;
"VCCD_HV7"
$PN"AV36"3;
"VCCD_HV8"
$PN"AV53"3;
"VCCD_HV9"
$PN"AV55"3;
"VCCD_HV10"
$PN"BA3"3;
"VCCD_HV11"
$PN"BA7"3;
"VCCD_HV12"
$PN"BE11"3;
"VCCD_HV13"
$PN"BE3"3;
"VCCD_HV14"
$PN"BE7"3;
"VCCD_HV15"
$PN"BJ11"3;
"VCCD_HV16"
$PN"BJ3"3;
"VCCD_HV17"
$PN"BJ7"3;
"VCCD_HV18"
$PN"BN7"3;
"VCCD_HV19"
$PN"CA7"3;
"VCCD_HV20"
$PN"CE7"3;
"VCCD_HV21"
$PN"CW35"3;
"VCCD_HV22"
$PN"CW37"3;
"VCCD_HV23"
$PN"CW52"3;
"VCCD_HV25"
$PN"CW56"3;
"VCCD_HV26"
$PN"CY34"3;
"VCCD_HV24"
$PN"CW54"3;
"VCCD_HV27"
$PN"CY36"3;
"VCCD_HV28"
$PN"CY53"3;
"VCC_3P3_AUX1"
$PN"BA21"6;
"VCC_3P3_AUX0"
$PN"BC21"6;
%"VCC_CORE"
"1","(2050,1675)","0","logical_power","I9";
;
HDL_POWER"PVNN_MAIN_CPU1"
CDS_LIB"logical_power";
"A"4;
END.
